#ISCELL
  mstr_misc dns *
  *
#ISCELL
  mstr_symbols cad_note *
  *
#ISCELL
  mstr_symbols design_note *
  *
#ISCELL
  mstr_symbols intel_corp_bpage *
  *
#ISCELL
  mstr_symbols p3v3_stby *
  page135_i106
#CELL
  mstr_discrete res *
  page135_i107
#ISCELL
  mstr_standard offpage *
  page135_i108
#ISCELL
  mstr_standard offpage *
  page135_i109
#ISCELL
  mstr_standard offpage *
  page135_i110
#ISCELL
  mstr_symbols p3v3_stby *
  page135_i111
#CELL
  mstr_discrete res *
  page135_i112
#CELL
  mstr_discrete res *
  page135_i113
#ISCELL
  mstr_symbols gnd *
  page135_i114
#ISCELL
  mstr_standard offpage *
  page135_i115
#ISCELL
  mstr_symbols p3v3_stby *
  page135_i116
#CELL
  mstr_discrete res *
  page135_i117
#CELL
  mstr_discrete res *
  page135_i118
#ISCELL
  mstr_symbols p3v3_stby *
  page135_i119
#CELL
  mstr_discrete res *
  page135_i120
#CELL
  mstr_discrete res *
  page135_i121
#ISCELL
  mstr_symbols p3v3_stby *
  page135_i122
#ISCELL
  mstr_symbols gnd *
  page135_i123
#CELL
  mstr_conn conn12_c73564003 *
  page135_i124
#ISCELL
  mstr_symbols gnd *
  page135_i125
#ISCELL
  mstr_standard offpage *
  page135_i126
#ISCELL
  mstr_standard offpage *
  page135_i127
#ISCELL
  mstr_symbols p3v3_stby *
  page135_i128
#CELL
  mstr_discrete res *
  page135_i129
#ISCELL
  mstr_symbols gnd *
  page135_i130
#CELL
  mstr_conn conn4_d42317002 *
  page135_i131
